# TIMECARD (Time Appliance Project (Time Card)) — schematic netlist excerpt (pin names and nets, part order shuffled) for the footprints in the layout excerpt that follows; sources: Cadence DE-HDL packaged netlist, KiCad conversion of R4006-B0001-02_R01.brd

R88  RESISTOR  0OHM -  pkg SMC_0402R_H016  page 21 : \1\ = FPGA_IN_MAC_PPS_OUTN ; \2\ = R_MAC_PPS_OUTN
C46  CAPACITOR  0.1UF 10V 10%  pkg SMC_0402R_H022  page 28 : \1\ = XP3R3V_EN ; \2\ = SG

(kicad_pcb
	(version 20260206)
	(generator "pcbnew")
	(generator_version "10.0")
	(general
		(thickness 1.6)
		(legacy_teardrops no)
	)
	(paper "A4")
	(title_block
		(title "timecard-production-celestica-r4006 — R4006-B0001-02_R01.brd")
		(comment 1 "Time Appliance Project (Time Card) / footprints 588-589 of 1113")
	)
	(layers
		(0 "F.Cu" signal "TOP")
		(4 "In1.Cu" signal "L02_GND1")
		(6 "In2.Cu" signal "L03_SIG1")
		(8 "In3.Cu" signal "L04_GND2")
		(10 "In4.Cu" signal "L05_VCC1")
		(12 "In5.Cu" signal "L06_VCC2")
		(14 "In6.Cu" signal "L07_GND3")
		(16 "In7.Cu" signal "L08_SIG2")
		(18 "In8.Cu" signal "L09_GND4")
		(2 "B.Cu" signal "BOTTOM")
		(9 "F.Adhes" user "F.Adhesive")
		(11 "B.Adhes" user "B.Adhesive")
		(13 "F.Paste" user "Package Geometry/Pastemask Top")
		(15 "B.Paste" user "Package Geometry/Pastemask Bottom")
		(5 "F.SilkS" user "Ref Des/Silkscreen Top")
		(7 "B.SilkS" user "Ref Des/Silkscreen Bottom")
		(1 "F.Mask" user "Board Geometry/Soldermask Top")
		(3 "B.Mask" user "Board Geometry/Soldermask Bottom")
		(17 "Dwgs.User" user "User.Drawings")
		(19 "Cmts.User" user "User.Comments")
		(21 "Eco1.User" user "User.Eco1")
		(23 "Eco2.User" user "User.Eco2")
		(25 "Edge.Cuts" user "Board Geometry/Outline")
		(27 "Margin" user)
		(31 "F.CrtYd" user "Package Geometry/Place Bound Top")
		(29 "B.CrtYd" user "Package Geometry/Place Bound Bottom")
		(35 "F.Fab" user "Ref Des/Assembly Top")
		(33 "B.Fab" user "Ref Des/Assembly Bottom")
	)
	(footprint ""
		(layer "F.Cu")
		(at 89.9922 -102.4128)
		(property "Reference" "C46"
			(at 3.048 0.16637 0)
			(unlocked yes)
			(layer "F.SilkS")
			(effects
				(font
					(size 0.7874 0.5842)
					(thickness 0.1524)
				)
			)
		)
		(property "Value" "VAL*"
			(at 0.0762 2.067306 0)
			(unlocked yes)
			(layer "F.Fab")
			(hide yes)
			(effects
				(font
					(size 0.7874 0.5842)
					(thickness 0.1524)
				)
			)
		)
		(property "Tolerance" "TOL*"
			(at 0.0762 3.032506 0)
			(unlocked yes)
			(layer "Cmts.User")
			(hide yes)
			(effects
				(font
					(size 0.7874 0.5842)
					(thickness 0.1524)
				)
			)
		)
		(property "User Part Number" "PARTNUM*"
			(at 0.1016 4.023106 0)
			(unlocked yes)
			(layer "Cmts.User")
			(hide yes)
			(effects
				(font
					(size 0.7874 0.5842)
					(thickness 0.1524)
				)
			)
		)
		(property "Device Type" "CAPACITOR-G105-0B104-CK,0.1UF,A"
			(at 0.0508 1.127506 0)
			(unlocked yes)
			(layer "F.Fab")
			(hide yes)
			(effects
				(font
					(size 0.7874 0.5842)
					(thickness 0.1524)
				)
			)
		)
		(duplicate_pad_numbers_are_jumpers no)
		(fp_line
			(start -1.143 -0.5588)
			(end -1.143 0.5588)
			(stroke
				(width 0.1)
				(type default)
			)
			(layer "F.SilkS")
		)
		(fp_line
			(start -1.143 0.5588)
			(end 1.143 0.5588)
			(stroke
				(width 0.1)
				(type default)
			)
			(layer "F.SilkS")
		)
		(fp_line
			(start 1.143 -0.5588)
			(end -1.143 -0.5588)
			(stroke
				(width 0.1)
				(type default)
			)
			(layer "F.SilkS")
		)
		(fp_line
			(start 1.143 0.5588)
			(end 1.143 -0.5588)
			(stroke
				(width 0.1)
				(type default)
			)
			(layer "F.SilkS")
		)
		(fp_rect
			(start -1.143 0.5588)
			(end 1.143 -0.5588)
			(stroke
				(width 0)
				(type default)
			)
			(fill no)
			(layer "F.CrtYd")
		)
		(fp_line
			(start -0.508 -0.3048)
			(end -0.508 0.3048)
			(stroke
				(width 0.1)
				(type default)
			)
			(layer "F.Fab")
		)
		(fp_line
			(start -0.508 0.3048)
			(end 0.508 0.3048)
			(stroke
				(width 0.1)
				(type default)
			)
			(layer "F.Fab")
		)
		(fp_line
			(start 0.508 -0.3048)
			(end -0.508 -0.3048)
			(stroke
				(width 0.1)
				(type default)
			)
			(layer "F.Fab")
		)
		(fp_line
			(start 0.508 0.3048)
			(end 0.508 -0.3048)
			(stroke
				(width 0.1)
				(type default)
			)
			(layer "F.Fab")
		)
		(pad "1" smd rect
			(at -0.5334 0)
			(size 0.7112 0.6096)
			(layers "F.Cu" "F.Mask" "F.Paste")
			(net "XP3R3V_EN")
		)
		(pad "2" smd rect
			(at 0.5334 0)
			(size 0.7112 0.6096)
			(layers "F.Cu" "F.Mask" "F.Paste")
			(net "SG")
		)
		(zone
			(layer "F.Cu")
			(hatch none 0.5)
			(connect_pads
				(clearance 0)
			)
			(min_thickness 0.25)
			(keepout
				(tracks allowed)
				(vias not_allowed)
				(pads allowed)
				(copperpour not_allowed)
				(footprints allowed)
			)
			(placement
				(enabled no)
				(sheetname "")
			)
			(fill
				(thermal_gap 0.5)
				(thermal_bridge_width 0.5)
				(island_removal_mode 0)
			)
			(polygon
				(pts
					(xy 89.916 -102.108) (xy 90.0684 -102.108) (xy 90.0684 -102.7176) (xy 89.916 -102.7176)
				)
			)
		)
	)
	(footprint ""
		(layer "F.Cu")
		(at 79.8576 -44.45 180)
		(property "Reference" "R88"
			(at -0.0254 -14.00937 0)
			(unlocked yes)
			(layer "F.SilkS")
			(effects
				(font
					(size 0.7874 0.5842)
					(thickness 0.1524)
				)
			)
		)
		(property "Value" "VAL*"
			(at 0.02032 2.13233 180)
			(unlocked yes)
			(layer "F.Fab")
			(hide yes)
			(effects
				(font
					(size 0.7874 0.5842)
					(thickness 0.1524)
				)
			)
		)
		(property "Device Type" "RESISTOR-G155-100R0-J0,0OHM,-"
			(at 0.008382 1.210564 180)
			(unlocked yes)
			(layer "F.Fab")
			(hide yes)
			(effects
				(font
					(size 0.7874 0.5842)
					(thickness 0.1524)
				)
			)
		)
		(property "User Part Number" "PARTNUM*"
			(at 0.02032 4.024884 180)
			(unlocked yes)
			(layer "Cmts.User")
			(hide yes)
			(effects
				(font
					(size 0.7874 0.5842)
					(thickness 0.1524)
				)
			)
		)
		(property "Tolerance" "TOL*"
			(at 0.044704 3.05435 180)
			(unlocked yes)
			(layer "Cmts.User")
			(hide yes)
			(effects
				(font
					(size 0.7874 0.5842)
					(thickness 0.1524)
				)
			)
		)
		(duplicate_pad_numbers_are_jumpers no)
		(fp_line
			(start 1.143 0.5588)
			(end 1.143 -0.5588)
			(stroke
				(width 0.1)
				(type default)
			)
			(layer "F.SilkS")
		)
		(fp_line
			(start 1.143 -0.5588)
			(end -1.143 -0.5588)
			(stroke
				(width 0.1)
				(type default)
			)
			(layer "F.SilkS")
		)
		(fp_line
			(start -1.143 0.5588)
			(end 1.143 0.5588)
			(stroke
				(width 0.1)
				(type default)
			)
			(layer "F.SilkS")
		)
		(fp_line
			(start -1.143 -0.5588)
			(end -1.143 0.5588)
			(stroke
				(width 0.1)
				(type default)
			)
			(layer "F.SilkS")
		)
		(fp_rect
			(start 1.143 -0.5588)
			(end -1.143 0.5588)
			(stroke
				(width 0)
				(type default)
			)
			(fill no)
			(layer "F.CrtYd")
		)
		(fp_line
			(start 0.508 0.3048)
			(end 0.508 -0.3048)
			(stroke
				(width 0.1)
				(type default)
			)
			(layer "F.Fab")
		)
		(fp_line
			(start 0.508 -0.3048)
			(end -0.508 -0.3048)
			(stroke
				(width 0.1)
				(type default)
			)
			(layer "F.Fab")
		)
		(fp_line
			(start -0.508 0.3048)
			(end 0.508 0.3048)
			(stroke
				(width 0.1)
				(type default)
			)
			(layer "F.Fab")
		)
		(fp_line
			(start -0.508 -0.3048)
			(end -0.508 0.3048)
			(stroke
				(width 0.1)
				(type default)
			)
			(layer "F.Fab")
		)
		(pad "1" smd rect
			(at -0.5334 0 180)
			(size 0.7112 0.6096)
			(layers "F.Cu" "F.Mask" "F.Paste")
			(net "FPGA_IN_MAC_PPS_OUTN")
		)
		(pad "2" smd rect
			(at 0.5334 0 180)
			(size 0.7112 0.6096)
			(layers "F.Cu" "F.Mask" "F.Paste")
			(net "R_MAC_PPS_OUTN")
		)
		(zone
			(layer "F.Cu")
			(hatch none 0.5)
			(connect_pads
				(clearance 0)
			)
			(min_thickness 0.25)
			(keepout
				(tracks allowed)
				(vias not_allowed)
				(pads allowed)
				(copperpour not_allowed)
				(footprints allowed)
			)
			(placement
				(enabled no)
				(sheetname "")
			)
			(fill
				(thermal_gap 0.5)
				(thermal_bridge_width 0.5)
				(island_removal_mode 0)
			)
			(polygon
				(pts
					(xy 79.7814 -44.1452) (xy 79.9338 -44.1452) (xy 79.9338 -44.7548) (xy 79.7814 -44.7548)
				)
			)
		)
	)
)
